(kicad_pcb
	(version 20260206)
	(generator "pcbnew")
	(generator_version "10.0")
	(general
		(thickness 1.6)
		(legacy_teardrops no)
	)
	(paper "A4")
	(title_block
		(title "15969-1a.1015WZS0858.brd")
		(comment 1 "Tioga Pass / footprints 174-180 of 295")
	)
	(layers
		(0 "F.Cu" signal "TOP")
		(4 "In1.Cu" signal "L2GND")
		(6 "In2.Cu" signal "L3")
		(8 "In3.Cu" signal "L4")
		(10 "In4.Cu" signal "L5GND")
		(2 "B.Cu" signal "BOTTOM")
		(9 "F.Adhes" user "F.Adhesive")
		(11 "B.Adhes" user "B.Adhesive")
		(13 "F.Paste" user "Package Geometry/Pastemask Top")
		(15 "B.Paste" user "Package Geometry/Pastemask Bottom")
		(5 "F.SilkS" user "Ref Des/Silkscreen Top")
		(7 "B.SilkS" user "Ref Des/Silkscreen Bottom")
		(1 "F.Mask" user "Board Geometry/Soldermask Top")
		(3 "B.Mask" user "Board Geometry/Soldermask Bottom")
		(17 "Dwgs.User" user "User.Drawings")
		(19 "Cmts.User" user "User.Comments")
		(21 "Eco1.User" user "User.Eco1")
		(23 "Eco2.User" user "User.Eco2")
		(25 "Edge.Cuts" user "Board Geometry/Outline")
		(27 "Margin" user)
		(31 "F.CrtYd" user "Package Geometry/Place Bound Top")
		(29 "B.CrtYd" user "Package Geometry/Place Bound Bottom")
		(35 "F.Fab" user "Ref Des/Assembly Top")
		(33 "B.Fab" user "Ref Des/Assembly Bottom")
	)
	(footprint ""
		(layer "F.Cu")
		(at 18.5928 -23.4696 180)
		(property "Reference" "C49"
			(at 0 0 180)
			(layer "F.SilkS")
			(hide yes)
			(effects
				(font
					(size 1.27 1.27)
				)
			)
		)
		(property "Value" "SCD1U25V2KX-2-GP"
			(at 1.1811 -2.7051 180)
			(unlocked yes)
			(layer "F.Fab")
			(hide yes)
			(effects
				(font
					(size 1.016 1.016)
					(thickness 0.1524)
				)
			)
		)
		(property "Device Type" "C402H22"
			(at 1.1811 -4.2291 180)
			(unlocked yes)
			(layer "F.Fab")
			(hide yes)
			(effects
				(font
					(size 1.016 1.016)
					(thickness 0.1524)
				)
			)
		)
		(duplicate_pad_numbers_are_jumpers no)
		(fp_rect
			(start -0.4318 0.9525)
			(end 0.4318 -0.9525)
			(stroke
				(width 0)
				(type default)
			)
			(fill no)
			(layer "F.CrtYd")
		)
		(fp_rect
			(start -0.4318 0.9525)
			(end 0.4318 -0.9525)
			(stroke
				(width 0)
				(type default)
			)
			(fill no)
			(layer "F.Fab")
		)
		(pad "1" smd custom
			(at 0 -0.4445 180)
			(size 0.1524 0.1524)
			(layers "F.Cu" "F.Mask" "F.Paste")
			(net "SLOT3_P12V_SENSE_VP_R")
			(options
				(clearance outline)
				(anchor circle)
			)
			(primitives
				(gr_poly
					(pts
						(arc
							(start 0.3048 -0.2032)
							(mid 0.275042 -0.275042)
							(end 0.2032 -0.3048)
						)
						(arc
							(start -0.2032 -0.3048)
							(mid -0.275042 -0.275042)
							(end -0.3048 -0.2032)
						)
						(arc
							(start -0.3048 0.2032)
							(mid -0.275042 0.275042)
							(end -0.2032 0.3048)
						)
						(arc
							(start 0.2032 0.3048)
							(mid 0.275042 0.275042)
							(end 0.3048 0.2032)
						)
					)
					(width 0)
					(fill yes)
				)
			)
		)
		(pad "2" smd custom
			(at 0 0.4445 180)
			(size 0.1524 0.1524)
			(layers "F.Cu" "F.Mask" "F.Paste")
			(net "SLOT3_P12V_SENSE_VN_R")
			(options
				(clearance outline)
				(anchor circle)
			)
			(primitives
				(gr_poly
					(pts
						(arc
							(start 0.3048 -0.2032)
							(mid 0.275042 -0.275042)
							(end 0.2032 -0.3048)
						)
						(arc
							(start -0.2032 -0.3048)
							(mid -0.275042 -0.275042)
							(end -0.3048 -0.2032)
						)
						(arc
							(start -0.3048 0.2032)
							(mid -0.275042 0.275042)
							(end -0.2032 0.3048)
						)
						(arc
							(start 0.2032 0.3048)
							(mid 0.275042 0.275042)
							(end 0.3048 0.2032)
						)
					)
					(width 0)
					(fill yes)
				)
			)
		)
	)
	(footprint ""
		(layer "B.Cu")
		(at 15.1257 -27.3177 -45)
		(property "Reference" "R103"
			(at 0 0 135)
			(layer "B.SilkS")
			(hide yes)
			(effects
				(font
					(size 1.27 1.27)
				)
				(justify mirror)
			)
		)
		(property "Value" "10R2F-L-GP"
			(at -0.06376 -3.993804 315)
			(unlocked yes)
			(layer "B.Fab")
			(hide yes)
			(effects
				(font
					(size 1.016 1.016)
					(thickness 0.1524)
				)
				(justify mirror)
			)
		)
		(property "Device Type" "R402H14"
			(at -0.064119 -5.517933 315)
			(unlocked yes)
			(layer "B.Fab")
			(hide yes)
			(effects
				(font
					(size 1.016 1.016)
					(thickness 0.1524)
				)
				(justify mirror)
			)
		)
		(duplicate_pad_numbers_are_jumpers no)
		(fp_line
			(start -0.508103 -0.939874)
			(end 0.508282 -0.939694)
			(stroke
				(width 0.1524)
				(type default)
			)
			(layer "B.SilkS")
		)
		(fp_line
			(start 0.508282 -0.939694)
			(end 0.508282 0.940053)
			(stroke
				(width 0.1524)
				(type default)
			)
			(layer "B.SilkS")
		)
		(fp_poly
			(pts
				(xy -0.507717 0.940053) (xy -0.507718 -0.939546) (xy 0.508282 -0.939547) (xy 0.508282 0.940053)
			)
			(stroke
				(width 0)
				(type default)
			)
			(fill no)
			(layer "B.CrtYd")
		)
		(fp_poly
			(pts
				(xy -0.507717 0.940053) (xy -0.507718 -0.939546) (xy 0.508282 -0.939547) (xy 0.508282 0.940053)
			)
			(stroke
				(width 0)
				(type default)
			)
			(fill no)
			(layer "B.Fab")
		)
		(pad "1" smd custom
			(at 0 -0.4445 135)
			(size 0.1397 0.1397)
			(layers "B.Cu" "B.Mask" "B.Paste")
			(net "P12V_ATX")
			(options
				(clearance outline)
				(anchor circle)
			)
			(primitives
				(gr_poly
					(pts
						(arc
							(start -0.1778 0.2794)
							(mid -0.249642 0.249642)
							(end -0.2794 0.1778)
						)
						(arc
							(start -0.2794 -0.1778)
							(mid -0.249642 -0.249642)
							(end -0.1778 -0.2794)
						)
						(arc
							(start 0.1778 -0.2794)
							(mid 0.249642 -0.249642)
							(end 0.2794 -0.1778)
						)
						(arc
							(start 0.2794 0.1778)
							(mid 0.249642 0.249642)
							(end 0.1778 0.2794)
						)
					)
					(width 0)
					(fill yes)
				)
			)
		)
		(pad "2" smd custom
			(at 0 0.4445 135)
			(size 0.1397 0.1397)
			(layers "B.Cu" "B.Mask" "B.Paste")
			(net "ATX_P12V_SENSE_VN_R")
			(options
				(clearance outline)
				(anchor circle)
			)
			(primitives
				(gr_poly
					(pts
						(arc
							(start -0.1778 0.2794)
							(mid -0.249642 0.249642)
							(end -0.2794 0.1778)
						)
						(arc
							(start -0.2794 -0.1778)
							(mid -0.249642 -0.249642)
							(end -0.1778 -0.2794)
						)
						(arc
							(start 0.1778 -0.2794)
							(mid 0.249642 -0.249642)
							(end 0.2794 -0.1778)
						)
						(arc
							(start 0.2794 0.1778)
							(mid 0.249642 0.249642)
							(end 0.1778 0.2794)
						)
					)
					(width 0)
					(fill yes)
				)
			)
		)
	)
	(footprint ""
		(layer "B.Cu")
		(at 26.3652 -25.6032 180)
		(property "Reference" "R148"
			(at 0 0 0)
			(layer "B.SilkS")
			(hide yes)
			(effects
				(font
					(size 1.27 1.27)
				)
				(justify mirror)
			)
		)
		(property "Value" "10KR2F-2-GP"
			(at -0.064008 -3.993896 180)
			(unlocked yes)
			(layer "B.Fab")
			(hide yes)
			(effects
				(font
					(size 1.016 1.016)
					(thickness 0.1524)
				)
				(justify mirror)
			)
		)
		(property "Device Type" "R402H16"
			(at -0.064008 -5.517896 180)
			(unlocked yes)
			(layer "B.Fab")
			(hide yes)
			(effects
				(font
					(size 1.016 1.016)
					(thickness 0.1524)
				)
				(justify mirror)
			)
		)
		(duplicate_pad_numbers_are_jumpers no)
		(fp_line
			(start 0.508 -0.9398)
			(end 0.508 0.9398)
			(stroke
				(width 0.1524)
				(type default)
			)
			(layer "B.SilkS")
		)
		(fp_line
			(start -0.508 -0.9398)
			(end 0.508 -0.9398)
			(stroke
				(width 0.1524)
				(type default)
			)
			(layer "B.SilkS")
		)
		(fp_rect
			(start 0.508 0.9398)
			(end -0.508 -0.9398)
			(stroke
				(width 0)
				(type default)
			)
			(fill no)
			(layer "B.CrtYd")
		)
		(fp_rect
			(start 0.508 0.9398)
			(end -0.508 -0.9398)
			(stroke
				(width 0)
				(type default)
			)
			(fill no)
			(layer "B.Fab")
		)
		(pad "1" smd custom
			(at 0 -0.4445)
			(size 0.1397 0.1397)
			(layers "B.Cu" "B.Mask" "B.Paste")
			(net "P3V3_STBY")
			(options
				(clearance outline)
				(anchor circle)
			)
			(primitives
				(gr_poly
					(pts
						(arc
							(start -0.1778 0.2794)
							(mid -0.249642 0.249642)
							(end -0.2794 0.1778)
						)
						(arc
							(start -0.2794 -0.1778)
							(mid -0.249642 -0.249642)
							(end -0.1778 -0.2794)
						)
						(arc
							(start 0.1778 -0.2794)
							(mid 0.249642 -0.249642)
							(end 0.2794 -0.1778)
						)
						(arc
							(start 0.2794 0.1778)
							(mid 0.249642 0.249642)
							(end 0.1778 0.2794)
						)
					)
					(width 0)
					(fill yes)
				)
			)
		)
		(pad "2" smd custom
			(at 0 0.4445)
			(size 0.1397 0.1397)
			(layers "B.Cu" "B.Mask" "B.Paste")
			(net "ATX_VMONITOR_A1")
			(options
				(clearance outline)
				(anchor circle)
			)
			(primitives
				(gr_poly
					(pts
						(arc
							(start -0.1778 0.2794)
							(mid -0.249642 0.249642)
							(end -0.2794 0.1778)
						)
						(arc
							(start -0.2794 -0.1778)
							(mid -0.249642 -0.249642)
							(end -0.1778 -0.2794)
						)
						(arc
							(start 0.1778 -0.2794)
							(mid 0.249642 -0.249642)
							(end 0.2794 -0.1778)
						)
						(arc
							(start 0.2794 0.1778)
							(mid 0.249642 0.249642)
							(end 0.1778 0.2794)
						)
					)
					(width 0)
					(fill yes)
				)
			)
		)
	)
	(footprint ""
		(layer "B.Cu")
		(at 117.7925 -2.35712)
		(property "Reference" "R59"
			(at 0 0 0)
			(layer "B.SilkS")
			(hide yes)
			(effects
				(font
					(size 1.27 1.27)
				)
				(justify mirror)
			)
		)
		(property "Value" "10KR2F-2-GP"
			(at -0.064008 -3.993896 0)
			(unlocked yes)
			(layer "B.Fab")
			(hide yes)
			(effects
				(font
					(size 1.016 1.016)
					(thickness 0.1524)
				)
				(justify mirror)
			)
		)
		(property "Device Type" "R402H16"
			(at -0.064008 -5.517896 0)
			(unlocked yes)
			(layer "B.Fab")
			(hide yes)
			(effects
				(font
					(size 1.016 1.016)
					(thickness 0.1524)
				)
				(justify mirror)
			)
		)
		(duplicate_pad_numbers_are_jumpers no)
		(fp_line
			(start -0.508 -0.9398)
			(end 0.508 -0.9398)
			(stroke
				(width 0.1524)
				(type default)
			)
			(layer "B.SilkS")
		)
		(fp_line
			(start 0.508 -0.9398)
			(end 0.508 0.9398)
			(stroke
				(width 0.1524)
				(type default)
			)
			(layer "B.SilkS")
		)
		(fp_rect
			(start 0.508 0.9398)
			(end -0.508 -0.9398)
			(stroke
				(width 0)
				(type default)
			)
			(fill no)
			(layer "B.CrtYd")
		)
		(fp_rect
			(start 0.508 0.9398)
			(end -0.508 -0.9398)
			(stroke
				(width 0)
				(type default)
			)
			(fill no)
			(layer "B.Fab")
		)
		(pad "1" smd custom
			(at 0 -0.4445 180)
			(size 0.1397 0.1397)
			(layers "B.Cu" "B.Mask" "B.Paste")
			(net "SMB_BMC_DEVICE_ALERT_N")
			(options
				(clearance outline)
				(anchor circle)
			)
			(primitives
				(gr_poly
					(pts
						(arc
							(start -0.1778 0.2794)
							(mid -0.249642 0.249642)
							(end -0.2794 0.1778)
						)
						(arc
							(start -0.2794 -0.1778)
							(mid -0.249642 -0.249642)
							(end -0.1778 -0.2794)
						)
						(arc
							(start 0.1778 -0.2794)
							(mid 0.249642 -0.249642)
							(end 0.2794 -0.1778)
						)
						(arc
							(start 0.2794 0.1778)
							(mid 0.249642 0.249642)
							(end 0.1778 0.2794)
						)
					)
					(width 0)
					(fill yes)
				)
			)
		)
		(pad "2" smd custom
			(at 0 0.4445 180)
			(size 0.1397 0.1397)
			(layers "B.Cu" "B.Mask" "B.Paste")
			(net "P3V3_STBY")
			(options
				(clearance outline)
				(anchor circle)
			)
			(primitives
				(gr_poly
					(pts
						(arc
							(start -0.1778 0.2794)
							(mid -0.249642 0.249642)
							(end -0.2794 0.1778)
						)
						(arc
							(start -0.2794 -0.1778)
							(mid -0.249642 -0.249642)
							(end -0.1778 -0.2794)
						)
						(arc
							(start 0.1778 -0.2794)
							(mid 0.249642 -0.249642)
							(end 0.2794 -0.1778)
						)
						(arc
							(start 0.2794 0.1778)
							(mid 0.249642 0.249642)
							(end 0.1778 0.2794)
						)
					)
					(width 0)
					(fill yes)
				)
			)
		)
	)
	(footprint ""
		(layer "B.Cu")
		(at 124.2822 -25.7048 180)
		(property "Reference" "CU7"
			(at 0 0 0)
			(layer "B.SilkS")
			(hide yes)
			(effects
				(font
					(size 1.27 1.27)
				)
				(justify mirror)
			)
		)
		(property "Value" "SC1U10V2KX-4-GP"
			(at -1.1811 -2.7051 180)
			(unlocked yes)
			(layer "B.Fab")
			(hide yes)
			(effects
				(font
					(size 1.016 1.016)
					(thickness 0.1524)
				)
				(justify mirror)
			)
		)
		(property "Device Type" "C402H22"
			(at -1.1811 -4.2291 180)
			(unlocked yes)
			(layer "B.Fab")
			(hide yes)
			(effects
				(font
					(size 1.016 1.016)
					(thickness 0.1524)
				)
				(justify mirror)
			)
		)
		(duplicate_pad_numbers_are_jumpers no)
		(fp_rect
			(start 0.4318 0.9525)
			(end -0.4318 -0.9525)
			(stroke
				(width 0)
				(type default)
			)
			(fill no)
			(layer "B.CrtYd")
		)
		(fp_rect
			(start 0.4318 0.9525)
			(end -0.4318 -0.9525)
			(stroke
				(width 0)
				(type default)
			)
			(fill no)
			(layer "B.Fab")
		)
		(pad "1" smd custom
			(at 0 -0.4445)
			(size 0.1524 0.1524)
			(layers "B.Cu" "B.Mask" "B.Paste")
			(net "P3V3_USB_HUB")
			(options
				(clearance outline)
				(anchor circle)
			)
			(primitives
				(gr_poly
					(pts
						(arc
							(start 0.3048 0.2032)
							(mid 0.275042 0.275042)
							(end 0.2032 0.3048)
						)
						(arc
							(start -0.2032 0.3048)
							(mid -0.275042 0.275042)
							(end -0.3048 0.2032)
						)
						(arc
							(start -0.3048 -0.2032)
							(mid -0.275042 -0.275042)
							(end -0.2032 -0.3048)
						)
						(arc
							(start 0.2032 -0.3048)
							(mid 0.275042 -0.275042)
							(end 0.3048 -0.2032)
						)
					)
					(width 0)
					(fill yes)
				)
			)
		)
		(pad "2" smd custom
			(at 0 0.4445)
			(size 0.1524 0.1524)
			(layers "B.Cu" "B.Mask" "B.Paste")
			(net "GND")
			(options
				(clearance outline)
				(anchor circle)
			)
			(primitives
				(gr_poly
					(pts
						(arc
							(start 0.3048 0.2032)
							(mid 0.275042 0.275042)
							(end 0.2032 0.3048)
						)
						(arc
							(start -0.2032 0.3048)
							(mid -0.275042 0.275042)
							(end -0.3048 0.2032)
						)
						(arc
							(start -0.3048 -0.2032)
							(mid -0.275042 -0.275042)
							(end -0.2032 -0.3048)
						)
						(arc
							(start 0.2032 -0.3048)
							(mid 0.275042 -0.275042)
							(end 0.3048 -0.2032)
						)
					)
					(width 0)
					(fill yes)
				)
			)
		)
	)
	(footprint ""
		(layer "B.Cu")
		(at 120.92178 -4.68122 90)
		(property "Reference" "R20"
			(at 0 0 90)
			(layer "B.SilkS")
			(hide yes)
			(effects
				(font
					(size 1.27 1.27)
				)
				(justify mirror)
			)
		)
		(property "Value" "4K7R2F-GP"
			(at -0.064008 -3.993896 90)
			(unlocked yes)
			(layer "B.Fab")
			(hide yes)
			(effects
				(font
					(size 1.016 1.016)
					(thickness 0.1524)
				)
				(justify mirror)
			)
		)
		(property "Device Type" "R402H16"
			(at -0.064008 -5.517896 90)
			(unlocked yes)
			(layer "B.Fab")
			(hide yes)
			(effects
				(font
					(size 1.016 1.016)
					(thickness 0.1524)
				)
				(justify mirror)
			)
		)
		(duplicate_pad_numbers_are_jumpers no)
		(fp_line
			(start 0.508 -0.9398)
			(end 0.508 0.9398)
			(stroke
				(width 0.1524)
				(type default)
			)
			(layer "B.SilkS")
		)
		(fp_line
			(start -0.508 -0.9398)
			(end 0.508 -0.9398)
			(stroke
				(width 0.1524)
				(type default)
			)
			(layer "B.SilkS")
		)
		(fp_rect
			(start 0.508 0.9398)
			(end -0.508 -0.9398)
			(stroke
				(width 0)
				(type default)
			)
			(fill no)
			(layer "B.CrtYd")
		)
		(fp_rect
			(start 0.508 0.9398)
			(end -0.508 -0.9398)
			(stroke
				(width 0)
				(type default)
			)
			(fill no)
			(layer "B.Fab")
		)
		(pad "1" smd custom
			(at 0 -0.4445 270)
			(size 0.1397 0.1397)
			(layers "B.Cu" "B.Mask" "B.Paste")
			(net "P3V3_STBY")
			(options
				(clearance outline)
				(anchor circle)
			)
			(primitives
				(gr_poly
					(pts
						(arc
							(start -0.1778 0.2794)
							(mid -0.249642 0.249642)
							(end -0.2794 0.1778)
						)
						(arc
							(start -0.2794 -0.1778)
							(mid -0.249642 -0.249642)
							(end -0.1778 -0.2794)
						)
						(arc
							(start 0.1778 -0.2794)
							(mid 0.249642 -0.249642)
							(end 0.2794 -0.1778)
						)
						(arc
							(start 0.2794 0.1778)
							(mid 0.249642 0.249642)
							(end 0.1778 0.2794)
						)
					)
					(width 0)
					(fill yes)
				)
			)
		)
		(pad "2" smd custom
			(at 0 0.4445 270)
			(size 0.1397 0.1397)
			(layers "B.Cu" "B.Mask" "B.Paste")
			(net "SMDAT_PCH_SLOT2")
			(options
				(clearance outline)
				(anchor circle)
			)
			(primitives
				(gr_poly
					(pts
						(arc
							(start -0.1778 0.2794)
							(mid -0.249642 0.249642)
							(end -0.2794 0.1778)
						)
						(arc
							(start -0.2794 -0.1778)
							(mid -0.249642 -0.249642)
							(end -0.1778 -0.2794)
						)
						(arc
							(start 0.1778 -0.2794)
							(mid 0.249642 -0.249642)
							(end 0.2794 -0.1778)
						)
						(arc
							(start 0.2794 0.1778)
							(mid 0.249642 0.249642)
							(end 0.1778 0.2794)
						)
					)
					(width 0)
					(fill yes)
				)
			)
		)
	)
	(footprint ""
		(layer "B.Cu")
		(at 29.9085 -2.0066 180)
		(property "Reference" "PC8"
			(at 0 0 0)
			(layer "B.SilkS")
			(hide yes)
			(effects
				(font
					(size 1.27 1.27)
				)
				(justify mirror)
			)
		)
		(property "Value" "SC22U6D3V5MX-5-GP"
			(at 0.0762 -6.1214 180)
			(unlocked yes)
			(layer "B.Fab")
			(hide yes)
			(effects
				(font
					(size 1.016 1.016)
					(thickness 0.1524)
				)
				(justify mirror)
			)
		)
		(property "Device Type" "C805H56"
			(at 0.0762 -8.1534 180)
			(unlocked yes)
			(layer "B.Fab")
			(hide yes)
			(effects
				(font
					(size 1.016 1.016)
					(thickness 0.1524)
				)
				(justify mirror)
			)
		)
		(duplicate_pad_numbers_are_jumpers no)
		(fp_line
			(start -0.635 0)
			(end 0.635 0)
			(stroke
				(width 0.508)
				(type default)
			)
			(layer "B.SilkS")
		)
		(fp_rect
			(start 0.9652 1.778)
			(end -0.9652 -1.778)
			(stroke
				(width 0)
				(type default)
			)
			(fill no)
			(layer "B.CrtYd")
		)
		(fp_poly
			(pts
				(xy 0.9652 -1.778) (xy -0.9652 -1.778) (xy -0.9652 1.778) (xy 0.9652 1.778)
			)
			(stroke
				(width 0)
				(type default)
			)
			(fill no)
			(layer "B.Fab")
		)
		(pad "1" smd rect
			(at 0 -0.9652)
			(size 1.397 1.143)
			(layers "B.Cu" "B.Mask" "B.Paste")
			(net "P3V3_VR")
		)
		(pad "2" smd rect
			(at 0 0.9652)
			(size 1.397 1.143)
			(layers "B.Cu" "B.Mask" "B.Paste")
			(net "GND")
		)
	)
)
